FILE_TYPE = MULTI_PHYS_TABLE;

PART 'SN74LVC2G07DCKR'

{========================================================================================}
:VALUE             | PACK_TYPE | MATERIAL | PART_NUMBER      = STANDARD         | LIFECYCLE        | ENVCOMP | PART_NUMBER   | JEDEC_TYPE | CLASS | DESCRIPTION                      | HEIGHT   | COMPONENT_TYPE | LEAD_LENGTH | LPID | STATUS | RPL | AML | MANUF_PN          | DAY        ;
{========================================================================================}
 'SN74LVC2G07DCKR' | 'SMLF'    | 'IC'     | 'AL002G07006'(!) = 'End of Design'  | 'Comp-Approve'   | 'NO'    | 'AL002G07006' |'SC70-6'| 'IC'  | 'IC(6P) SN74LVC2G07DCKR(SC70-6)' | '.044IN' | ''             | ''          | ''   | ''     | ''  | ''  | 'SN74LVC2G07DCKR' | '20101228'
 'SN74LVC2G07DCKR' | 'SMLF'    | 'EMPTY'  | 'AL002G07006'(!) = 'End of Design'  | 'Comp-Approve'   | 'NO'    | 'AL002G07006' |'SC70-6'| 'IO'  | 'IC(6P) SN74LVC2G07DCKR(SC70-6)' | '.044IN' | ''             | ''          | ''   | ''     | ''  | ''  | 'SN74LVC2G07DCKR' | '20101228'

END_PART

END.

